# S9S_MB_2U (Grand Teton) — schematic netlist excerpt (pin names and nets, part order shuffled) for the footprints in the layout excerpt that follows; sources: Cadence DE-HDL packaged netlist, KiCad conversion of 03242023_DA0F0TMBIJ0_F0T_Motherboard_J_brd_V01_OCP.brd

PR3982  Q_RES  120K 1% CHIP  pkg 0402LF  page 303 : A = AGND_HSC ; B = HSC_MODE_3
PD107  DIODE_TVS  SMF14A IC  pkg SOD123F  page 162 : A = GND ; C = P12V_AUX

(kicad_pcb
	(version 20260206)
	(generator "pcbnew")
	(generator_version "10.0")
	(general
		(thickness 1.6)
		(legacy_teardrops no)
	)
	(paper "A4")
	(title_block
		(title "03242023_DA0F0TMBIJ0_F0T_Motherboard_J_brd_V01_OCP.brd")
		(comment 1 "Grand Teton / footprints 3745-3746 of 6105")
	)
	(layers
		(0 "F.Cu" signal "TOP")
		(4 "In1.Cu" signal "GND")
		(6 "In2.Cu" signal "IN1")
		(8 "In3.Cu" signal "GND1")
		(10 "In4.Cu" signal "IN2")
		(12 "In5.Cu" signal "GND2")
		(14 "In6.Cu" signal "IN3")
		(16 "In7.Cu" signal "GND3")
		(18 "In8.Cu" signal "VCC")
		(20 "In9.Cu" signal "VCC1")
		(22 "In10.Cu" signal "GND4")
		(24 "In11.Cu" signal "IN4")
		(26 "In12.Cu" signal "GND5")
		(28 "In13.Cu" signal "IN5")
		(30 "In14.Cu" signal "GND6")
		(32 "In15.Cu" signal "IN6")
		(34 "In16.Cu" signal "GND7")
		(2 "B.Cu" signal "BOTTOM")
		(9 "F.Adhes" user "F.Adhesive")
		(11 "B.Adhes" user "B.Adhesive")
		(13 "F.Paste" user "Package Geometry/Pastemask Top")
		(15 "B.Paste" user "Package Geometry/Pastemask Bottom")
		(5 "F.SilkS" user "Ref Des/Silkscreen Top")
		(7 "B.SilkS" user "Ref Des/Silkscreen Bottom")
		(1 "F.Mask" user "Board Geometry/Soldermask Top")
		(3 "B.Mask" user "Board Geometry/Soldermask Bottom")
		(17 "Dwgs.User" user "User.Drawings")
		(19 "Cmts.User" user "User.Comments")
		(21 "Eco1.User" user "User.Eco1")
		(23 "Eco2.User" user "User.Eco2")
		(25 "Edge.Cuts" user "Board Geometry/Outline")
		(27 "Margin" user)
		(31 "F.CrtYd" user "Package Geometry/Place Bound Top")
		(29 "B.CrtYd" user "Package Geometry/Place Bound Bottom")
		(35 "F.Fab" user "Ref Des/Assembly Top")
		(33 "B.Fab" user "Ref Des/Assembly Bottom")
	)
	(footprint ""
		(layer "F.Cu")
		(at 77.916278 -30.112462 -90)
		(property "Reference" "PD107"
			(at 0.280924 -1.999742 0)
			(unlocked yes)
			(layer "F.SilkS")
			(effects
				(font
					(size 0.7874 0.5842)
					(thickness 0.1524)
				)
				(justify left)
			)
		)
		(property "Value" ""
			(at 0 0 270)
			(layer "F.Fab")
			(effects
				(font
					(size 1.27 1.27)
				)
			)
		)
		(duplicate_pad_numbers_are_jumpers no)
		(fp_line
			(start -2.250186 0.999998)
			(end 2.631186 0.999998)
			(stroke
				(width 0.1524)
				(type default)
			)
			(layer "F.SilkS")
		)
		(fp_line
			(start 2.631186 0.999998)
			(end 2.631186 -0.999998)
			(stroke
				(width 0.1524)
				(type default)
			)
			(layer "F.SilkS")
		)
		(fp_line
			(start -0.381 0.3302)
			(end -0.381 -0.4318)
			(stroke
				(width 0.1524)
				(type default)
			)
			(layer "F.SilkS")
		)
		(fp_line
			(start -0.381 -0.0508)
			(end -0.6604 -0.0508)
			(stroke
				(width 0.1524)
				(type default)
			)
			(layer "F.SilkS")
		)
		(fp_line
			(start 0.381 -0.0508)
			(end -0.381 0.3302)
			(stroke
				(width 0.1524)
				(type default)
			)
			(layer "F.SilkS")
		)
		(fp_line
			(start 0.381 -0.0508)
			(end 0.635 -0.0508)
			(stroke
				(width 0.1524)
				(type default)
			)
			(layer "F.SilkS")
		)
		(fp_line
			(start -0.381 -0.4318)
			(end 0.381 -0.0508)
			(stroke
				(width 0.1524)
				(type default)
			)
			(layer "F.SilkS")
		)
		(fp_line
			(start 0.381 -0.4318)
			(end 0.381 0.3302)
			(stroke
				(width 0.1524)
				(type default)
			)
			(layer "F.SilkS")
		)
		(fp_line
			(start -2.250186 -0.999998)
			(end -2.250186 0.999998)
			(stroke
				(width 0.1524)
				(type default)
			)
			(layer "F.SilkS")
		)
		(fp_line
			(start 2.631186 -0.999998)
			(end -2.250186 -0.999998)
			(stroke
				(width 0.1524)
				(type default)
			)
			(layer "F.SilkS")
		)
		(fp_rect
			(start 2.6162 1.016)
			(end 2.1844 -0.9652)
			(stroke
				(width 0)
				(type default)
			)
			(fill yes)
			(layer "F.SilkS")
		)
		(fp_line
			(start -1.450086 0.999998)
			(end 1.450086 0.999998)
			(stroke
				(width 0.1)
				(type default)
			)
			(layer "F.Fab")
		)
		(fp_line
			(start 1.450086 0.999998)
			(end 1.450086 -0.999998)
			(stroke
				(width 0.1)
				(type default)
			)
			(layer "F.Fab")
		)
		(fp_line
			(start -1.450086 -0.999998)
			(end -1.450086 0.999998)
			(stroke
				(width 0.1)
				(type default)
			)
			(layer "F.Fab")
		)
		(fp_line
			(start 1.450086 -0.999998)
			(end -1.450086 -0.999998)
			(stroke
				(width 0.1)
				(type default)
			)
			(layer "F.Fab")
		)
		(fp_text user "+"
			(at -4.134866 -0.205232 270)
			(unlocked yes)
			(layer "F.SilkS")
			(effects
				(font
					(size 1.905 1.4224)
					(thickness 0.1524)
				)
				(justify left)
			)
		)
		(fp_text user "-"
			(at 2.4384 -0.22225 270)
			(unlocked yes)
			(layer "F.SilkS")
			(effects
				(font
					(size 1.905 1.4224)
					(thickness 0.1524)
				)
				(justify left)
			)
		)
		(fp_text user "+"
			(at -3.4798 -0.22225 270)
			(unlocked yes)
			(layer "F.Fab")
			(effects
				(font
					(size 1.905 1.4224)
					(thickness 0.1524)
				)
				(justify left)
			)
		)
		(fp_text user "-"
			(at 2.4384 -0.22225 270)
			(unlocked yes)
			(layer "F.Fab")
			(effects
				(font
					(size 1.905 1.4224)
					(thickness 0.1524)
				)
				(justify left)
			)
		)
		(pad "A" smd rect
			(at -1.450086 0 270)
			(size 1.3208 1.4224)
			(layers "F.Cu" "F.Mask" "F.Paste")
			(net "GND")
		)
		(pad "C" smd rect
			(at 1.450086 0 270)
			(size 1.3208 1.4224)
			(layers "F.Cu" "F.Mask" "F.Paste")
			(net "P12V_AUX")
		)
	)
	(footprint ""
		(layer "F.Cu")
		(at 226.733608 -407.871422 180)
		(property "Reference" "PR3982"
			(at 0 0 180)
			(layer "F.SilkS")
			(hide yes)
			(effects
				(font
					(size 1.27 1.27)
				)
			)
		)
		(property "Value" ""
			(at 0 0 180)
			(layer "F.Fab")
			(effects
				(font
					(size 1.27 1.27)
				)
			)
		)
		(duplicate_pad_numbers_are_jumpers no)
		(fp_line
			(start 0.7874 0.4064)
			(end -0.7874 0.4064)
			(stroke
				(width 0.1524)
				(type default)
			)
			(layer "F.SilkS")
		)
		(fp_line
			(start 0.7874 -0.4064)
			(end 0.7874 0.4064)
			(stroke
				(width 0.1524)
				(type default)
			)
			(layer "F.SilkS")
		)
		(fp_line
			(start -0.7874 0.4064)
			(end -0.7874 -0.4064)
			(stroke
				(width 0.1524)
				(type default)
			)
			(layer "F.SilkS")
		)
		(fp_line
			(start -0.7874 -0.4064)
			(end 0.7874 -0.4064)
			(stroke
				(width 0.1524)
				(type default)
			)
			(layer "F.SilkS")
		)
		(fp_line
			(start 0.67945 0.3048)
			(end 0.120396 0.3048)
			(stroke
				(width 0.1)
				(type default)
			)
			(layer "F.Fab")
		)
		(fp_line
			(start 0.67945 -0.3048)
			(end 0.67945 0.3048)
			(stroke
				(width 0.1)
				(type default)
			)
			(layer "F.Fab")
		)
		(fp_line
			(start 0.12065 -0.2794)
			(end 0.12065 -0.3048)
			(stroke
				(width 0.1)
				(type default)
			)
			(layer "F.Fab")
		)
		(fp_line
			(start 0.12065 -0.3048)
			(end 0.67945 -0.3048)
			(stroke
				(width 0.1)
				(type default)
			)
			(layer "F.Fab")
		)
		(fp_line
			(start 0.120396 0.3048)
			(end 0.120396 0.2794)
			(stroke
				(width 0.1)
				(type default)
			)
			(layer "F.Fab")
		)
		(fp_line
			(start 0.120396 0.2794)
			(end -0.12065 0.2794)
			(stroke
				(width 0.1)
				(type default)
			)
			(layer "F.Fab")
		)
		(fp_line
			(start -0.12065 0.3048)
			(end -0.67945 0.3048)
			(stroke
				(width 0.1)
				(type default)
			)
			(layer "F.Fab")
		)
		(fp_line
			(start -0.12065 0.2794)
			(end -0.12065 0.3048)
			(stroke
				(width 0.1)
				(type default)
			)
			(layer "F.Fab")
		)
		(fp_line
			(start -0.12065 -0.2794)
			(end 0.12065 -0.2794)
			(stroke
				(width 0.1)
				(type default)
			)
			(layer "F.Fab")
		)
		(fp_line
			(start -0.12065 -0.305054)
			(end -0.12065 -0.2794)
			(stroke
				(width 0.1)
				(type default)
			)
			(layer "F.Fab")
		)
		(fp_line
			(start -0.67945 0.3048)
			(end -0.67945 -0.305054)
			(stroke
				(width 0.1)
				(type default)
			)
			(layer "F.Fab")
		)
		(fp_line
			(start -0.67945 -0.305054)
			(end -0.12065 -0.305054)
			(stroke
				(width 0.1)
				(type default)
			)
			(layer "F.Fab")
		)
		(pad "1" smd circle
			(at -0.40005 0 180)
			(size 0 0)
			(layers "F.Cu" "F.Mask" "F.Paste")
			(net "AGND_HSC")
		)
		(pad "2" smd circle
			(at 0.40005 0 180)
			(size 0 0)
			(layers "F.Cu" "F.Mask" "F.Paste")
			(net "HSC_MODE_3")
		)
	)
)
